FILE_TYPE = MACRO_DRAWING;
SET COLOR_WIRE YELLOW;
SET COLOR_PROP ORANGE;
SET COLOR_DOT WHITE;
SET COLOR_ARC YELLOW;
SET COLOR_BODY GREEN;
SET COLOR_NOTE PURPLE;
SET PROP_DISPLAY VALUE;
SET PAGE_NUMBER P383;
FORCEADD TAP..1
(-7075 3575);
FORCEPROP 3 LASTPIN (-7125 3575) SIG_NAME P5E_CPU0_P0_RX_BUF_DP<10>
J 0
(-7115 3585);
DISPLAY 0.659574 (-7115 3585);
PAINT MONO (-7115 3585);
DISPLAY INVISIBLE (-7115 3585);
FORCEPROP 1 LASTPIN (-7125 3575) BN 10
J 0
(-7137 3583);
DISPLAY 0.680851 (-7137 3583);
PAINT GREEN (-7137 3583);
FORCEPROP 2 LAST CDS_LIB standard
J 0
(-7075 3575);
DISPLAY INVISIBLE (-7075 3575);
FORCEPROP 1 LAST BODY_TYPE PLUMBING
J 0
(-7075 3625);
DISPLAY 0.872340 (-7075 3625);
PAINT GREEN (-7075 3625);
DISPLAY INVISIBLE (-7075 3625);
FORCEPROP 1 LAST HDL_TAP TRUE
J 0
(-6750 3450);
DISPLAY 0.872340 (-6750 3450);
DISPLAY INVISIBLE (-6750 3450);
FORCEPROP 1 LAST PATH I10
J 0
(-7077 3575);
DISPLAY 0.872340 (-7077 3575);
PAINT GREEN (-7077 3575);
DISPLAY INVISIBLE (-7077 3575);
FORCEADD TAP..1
(-7075 3925);
FORCEPROP 3 LASTPIN (-7125 3925) SIG_NAME P5E_CPU0_P0_RX_BUF_DP<11>
J 0
(-7115 3935);
DISPLAY 0.659574 (-7115 3935);
PAINT MONO (-7115 3935);
DISPLAY INVISIBLE (-7115 3935);
FORCEPROP 1 LASTPIN (-7125 3925) BN 11
J 0
(-7137 3933);
DISPLAY 0.680851 (-7137 3933);
PAINT GREEN (-7137 3933);
FORCEPROP 2 LAST CDS_LIB standard
J 0
(-7075 3925);
DISPLAY INVISIBLE (-7075 3925);
FORCEPROP 1 LAST BODY_TYPE PLUMBING
J 0
(-7075 3975);
DISPLAY 0.872340 (-7075 3975);
PAINT GREEN (-7075 3975);
DISPLAY INVISIBLE (-7075 3975);
FORCEPROP 1 LAST HDL_TAP TRUE
J 0
(-6750 3800);
DISPLAY 0.872340 (-6750 3800);
DISPLAY INVISIBLE (-6750 3800);
FORCEPROP 1 LAST PATH I11
J 0
(-7077 3925);
DISPLAY 0.872340 (-7077 3925);
PAINT GREEN (-7077 3925);
DISPLAY INVISIBLE (-7077 3925);
FORCEADD TAP..1
(-6875 3825);
FORCEPROP 3 LASTPIN (-6925 3825) SIG_NAME P5E_CPU0_P0_RX_BUF_DN<11>
J 0
(-6915 3835);
DISPLAY 0.659574 (-6915 3835);
PAINT MONO (-6915 3835);
DISPLAY INVISIBLE (-6915 3835);
FORCEPROP 1 LASTPIN (-6925 3825) BN 11
J 0
(-6937 3833);
DISPLAY 0.680851 (-6937 3833);
PAINT GREEN (-6937 3833);
FORCEPROP 2 LAST CDS_LIB standard
J 0
(-6875 3825);
DISPLAY INVISIBLE (-6875 3825);
FORCEPROP 1 LAST BODY_TYPE PLUMBING
J 0
(-6875 3875);
DISPLAY 0.872340 (-6875 3875);
PAINT GREEN (-6875 3875);
DISPLAY INVISIBLE (-6875 3875);
FORCEPROP 1 LAST HDL_TAP TRUE
J 0
(-6550 3700);
DISPLAY 0.872340 (-6550 3700);
DISPLAY INVISIBLE (-6550 3700);
FORCEPROP 1 LAST PATH I12
J 0
(-6877 3825);
DISPLAY 0.872340 (-6877 3825);
PAINT GREEN (-6877 3825);
DISPLAY INVISIBLE (-6877 3825);
FORCEADD TAP..1
(-7075 4275);
FORCEPROP 3 LASTPIN (-7125 4275) SIG_NAME P5E_CPU0_P0_RX_BUF_DP<12>
J 0
(-7115 4285);
DISPLAY 0.659574 (-7115 4285);
PAINT MONO (-7115 4285);
DISPLAY INVISIBLE (-7115 4285);
FORCEPROP 1 LASTPIN (-7125 4275) BN 12
J 0
(-7137 4283);
DISPLAY 0.680851 (-7137 4283);
PAINT GREEN (-7137 4283);
FORCEPROP 2 LAST CDS_LIB standard
J 0
(-7075 4275);
DISPLAY INVISIBLE (-7075 4275);
FORCEPROP 1 LAST BODY_TYPE PLUMBING
J 0
(-7075 4325);
DISPLAY 0.872340 (-7075 4325);
PAINT GREEN (-7075 4325);
DISPLAY INVISIBLE (-7075 4325);
FORCEPROP 1 LAST HDL_TAP TRUE
J 0
(-6750 4150);
DISPLAY 0.872340 (-6750 4150);
DISPLAY INVISIBLE (-6750 4150);
FORCEPROP 1 LAST PATH I13
J 0
(-7077 4275);
DISPLAY 0.872340 (-7077 4275);
PAINT GREEN (-7077 4275);
DISPLAY INVISIBLE (-7077 4275);
FORCEADD TAP..1
(-6875 4175);
FORCEPROP 3 LASTPIN (-6925 4175) SIG_NAME P5E_CPU0_P0_RX_BUF_DN<12>
J 0
(-6915 4185);
DISPLAY 0.659574 (-6915 4185);
PAINT MONO (-6915 4185);
DISPLAY INVISIBLE (-6915 4185);
FORCEPROP 1 LASTPIN (-6925 4175) BN 12
J 0
(-6937 4183);
DISPLAY 0.680851 (-6937 4183);
PAINT GREEN (-6937 4183);
FORCEPROP 2 LAST CDS_LIB standard
J 0
(-6875 4175);
DISPLAY INVISIBLE (-6875 4175);
FORCEPROP 1 LAST BODY_TYPE PLUMBING
J 0
(-6875 4225);
DISPLAY 0.872340 (-6875 4225);
PAINT GREEN (-6875 4225);
DISPLAY INVISIBLE (-6875 4225);
FORCEPROP 1 LAST HDL_TAP TRUE
J 0
(-6550 4050);
DISPLAY 0.872340 (-6550 4050);
DISPLAY INVISIBLE (-6550 4050);
FORCEPROP 1 LAST PATH I14
J 0
(-6877 4175);
DISPLAY 0.872340 (-6877 4175);
PAINT GREEN (-6877 4175);
DISPLAY INVISIBLE (-6877 4175);
FORCEADD TAP..1
(-7075 4625);
FORCEPROP 3 LASTPIN (-7125 4625) SIG_NAME P5E_CPU0_P0_RX_BUF_DP<13>
J 0
(-7115 4635);
DISPLAY 0.659574 (-7115 4635);
PAINT MONO (-7115 4635);
DISPLAY INVISIBLE (-7115 4635);
FORCEPROP 1 LASTPIN (-7125 4625) BN 13
J 0
(-7137 4633);
DISPLAY 0.680851 (-7137 4633);
PAINT GREEN (-7137 4633);
FORCEPROP 2 LAST CDS_LIB standard
J 0
(-7075 4625);
DISPLAY INVISIBLE (-7075 4625);
FORCEPROP 1 LAST BODY_TYPE PLUMBING
J 0
(-7075 4675);
DISPLAY 0.872340 (-7075 4675);
PAINT GREEN (-7075 4675);
DISPLAY INVISIBLE (-7075 4675);
FORCEPROP 1 LAST HDL_TAP TRUE
J 0
(-6750 4500);
DISPLAY 0.872340 (-6750 4500);
DISPLAY INVISIBLE (-6750 4500);
FORCEPROP 1 LAST PATH I15
J 0
(-7077 4625);
DISPLAY 0.872340 (-7077 4625);
PAINT GREEN (-7077 4625);
DISPLAY INVISIBLE (-7077 4625);
FORCEADD TAP..1
(-7075 4975);
FORCEPROP 3 LASTPIN (-7125 4975) SIG_NAME P5E_CPU0_P0_RX_BUF_DP<14>
J 0
(-7115 4985);
DISPLAY 0.659574 (-7115 4985);
PAINT MONO (-7115 4985);
DISPLAY INVISIBLE (-7115 4985);
FORCEPROP 1 LASTPIN (-7125 4975) BN 14
J 0
(-7137 4983);
DISPLAY 0.680851 (-7137 4983);
PAINT GREEN (-7137 4983);
FORCEPROP 2 LAST CDS_LIB standard
J 0
(-7075 4975);
DISPLAY INVISIBLE (-7075 4975);
FORCEPROP 1 LAST BODY_TYPE PLUMBING
J 0
(-7075 5025);
DISPLAY 0.872340 (-7075 5025);
PAINT GREEN (-7075 5025);
DISPLAY INVISIBLE (-7075 5025);
FORCEPROP 1 LAST HDL_TAP TRUE
J 0
(-6750 4850);
DISPLAY 0.872340 (-6750 4850);
DISPLAY INVISIBLE (-6750 4850);
FORCEPROP 1 LAST PATH I16
J 0
(-7077 4975);
DISPLAY 0.872340 (-7077 4975);
PAINT GREEN (-7077 4975);
DISPLAY INVISIBLE (-7077 4975);
FORCEADD TAP..1
(-6875 4525);
FORCEPROP 3 LASTPIN (-6925 4525) SIG_NAME P5E_CPU0_P0_RX_BUF_DN<13>
J 0
(-6915 4535);
DISPLAY 0.659574 (-6915 4535);
PAINT MONO (-6915 4535);
DISPLAY INVISIBLE (-6915 4535);
FORCEPROP 1 LASTPIN (-6925 4525) BN 13
J 0
(-6937 4533);
DISPLAY 0.680851 (-6937 4533);
PAINT GREEN (-6937 4533);
FORCEPROP 2 LAST CDS_LIB standard
J 0
(-6875 4525);
DISPLAY INVISIBLE (-6875 4525);
FORCEPROP 1 LAST BODY_TYPE PLUMBING
J 0
(-6875 4575);
DISPLAY 0.872340 (-6875 4575);
PAINT GREEN (-6875 4575);
DISPLAY INVISIBLE (-6875 4575);
FORCEPROP 1 LAST HDL_TAP TRUE
J 0
(-6550 4400);
DISPLAY 0.872340 (-6550 4400);
DISPLAY INVISIBLE (-6550 4400);
FORCEPROP 1 LAST PATH I17
J 0
(-6877 4525);
DISPLAY 0.872340 (-6877 4525);
PAINT GREEN (-6877 4525);
DISPLAY INVISIBLE (-6877 4525);
FORCEADD TAP..1
(-6875 4875);
FORCEPROP 3 LASTPIN (-6925 4875) SIG_NAME P5E_CPU0_P0_RX_BUF_DN<14>
J 0
(-6915 4885);
DISPLAY 0.659574 (-6915 4885);
PAINT MONO (-6915 4885);
DISPLAY INVISIBLE (-6915 4885);
FORCEPROP 1 LASTPIN (-6925 4875) BN 14
J 0
(-6937 4883);
DISPLAY 0.680851 (-6937 4883);
PAINT GREEN (-6937 4883);
FORCEPROP 2 LAST CDS_LIB standard
J 0
(-6875 4875);
DISPLAY INVISIBLE (-6875 4875);
FORCEPROP 1 LAST BODY_TYPE PLUMBING
J 0
(-6875 4925);
DISPLAY 0.872340 (-6875 4925);
PAINT GREEN (-6875 4925);
DISPLAY INVISIBLE (-6875 4925);
FORCEPROP 1 LAST HDL_TAP TRUE
J 0
(-6550 4750);
DISPLAY 0.872340 (-6550 4750);
DISPLAY INVISIBLE (-6550 4750);
FORCEPROP 1 LAST PATH I18
J 0
(-6877 4875);
DISPLAY 0.872340 (-6877 4875);
PAINT GREEN (-6877 4875);
DISPLAY INVISIBLE (-6877 4875);
FORCEADD TAP..1
(-7075 5325);
FORCEPROP 3 LASTPIN (-7125 5325) SIG_NAME P5E_CPU0_P0_RX_BUF_DP<15>
J 0
(-7115 5335);
DISPLAY 0.659574 (-7115 5335);
PAINT MONO (-7115 5335);
DISPLAY INVISIBLE (-7115 5335);
FORCEPROP 1 LASTPIN (-7125 5325) BN 15
J 0
(-7137 5333);
DISPLAY 0.680851 (-7137 5333);
PAINT GREEN (-7137 5333);
FORCEPROP 2 LAST CDS_LIB standard
J 0
(-7075 5325);
DISPLAY INVISIBLE (-7075 5325);
FORCEPROP 1 LAST BODY_TYPE PLUMBING
J 0
(-7075 5375);
DISPLAY 0.872340 (-7075 5375);
PAINT GREEN (-7075 5375);
DISPLAY INVISIBLE (-7075 5375);
FORCEPROP 1 LAST HDL_TAP TRUE
J 0
(-6750 5200);
DISPLAY 0.872340 (-6750 5200);
DISPLAY INVISIBLE (-6750 5200);
FORCEPROP 1 LAST PATH I19
J 0
(-7077 5325);
DISPLAY 0.872340 (-7077 5325);
PAINT GREEN (-7077 5325);
DISPLAY INVISIBLE (-7077 5325);
FORCEADD TAP..1
(-6875 5225);
FORCEPROP 3 LASTPIN (-6925 5225) SIG_NAME P5E_CPU0_P0_RX_BUF_DN<15>
J 0
(-6915 5235);
DISPLAY 0.659574 (-6915 5235);
PAINT MONO (-6915 5235);
DISPLAY INVISIBLE (-6915 5235);
FORCEPROP 1 LASTPIN (-6925 5225) BN 15
J 0
(-6937 5233);
DISPLAY 0.680851 (-6937 5233);
PAINT GREEN (-6937 5233);
FORCEPROP 2 LAST CDS_LIB standard
J 0
(-6875 5225);
DISPLAY INVISIBLE (-6875 5225);
FORCEPROP 1 LAST BODY_TYPE PLUMBING
J 0
(-6875 5275);
DISPLAY 0.872340 (-6875 5275);
PAINT GREEN (-6875 5275);
DISPLAY INVISIBLE (-6875 5275);
FORCEPROP 1 LAST HDL_TAP TRUE
J 0
(-6550 5100);
DISPLAY 0.872340 (-6550 5100);
DISPLAY INVISIBLE (-6550 5100);
FORCEPROP 1 LAST PATH I20
J 0
(-6877 5225);
DISPLAY 0.872340 (-6877 5225);
PAINT GREEN (-6877 5225);
DISPLAY INVISIBLE (-6877 5225);
FORCEADD OFFPAGE..1
R 2
(-5850 5425);
FORCEPROP 2 LAST $XR0 117 
J 0
(-5664 5425);
DISPLAY 0.638298 (-5664 5425);
PAINT MONO (-5664 5425);
FORCEPROP 2 LAST CDS_LIB standard
J 0
(-5850 5425);
DISPLAY INVISIBLE (-5850 5425);
FORCEPROP 1 LAST OFFPAGE TRUE
J 2
(-6175 5300);
DISPLAY 0.872340 (-6175 5300);
DISPLAY INVISIBLE (-6175 5300);
FORCEPROP 1 LAST COMMENT_BODY TRUE
J 2
(-5975 5325);
DISPLAY 0.872340 (-5975 5325);
PAINT GREEN (-5975 5325);
DISPLAY INVISIBLE (-5975 5325);
FORCEPROP 2 LAST PATH I21
J 0
(-5675 5500);
DISPLAY 0.680851 (-5675 5500);
DISPLAY INVISIBLE (-5675 5500);
FORCEADD OFFPAGE..1
R 2
(-5850 5350);
FORCEPROP 2 LAST $XR0 117 
J 0
(-5664 5350);
DISPLAY 0.638298 (-5664 5350);
PAINT MONO (-5664 5350);
FORCEPROP 2 LAST CDS_LIB standard
J 0
(-5850 5350);
DISPLAY INVISIBLE (-5850 5350);
FORCEPROP 1 LAST OFFPAGE TRUE
J 2
(-6175 5225);
DISPLAY 0.872340 (-6175 5225);
DISPLAY INVISIBLE (-6175 5225);
FORCEPROP 1 LAST COMMENT_BODY TRUE
J 2
(-5975 5250);
DISPLAY 0.872340 (-5975 5250);
PAINT GREEN (-5975 5250);
DISPLAY INVISIBLE (-5975 5250);
FORCEPROP 2 LAST PATH I22
J 0
(-5675 5425);
DISPLAY 0.680851 (-5675 5425);
DISPLAY INVISIBLE (-5675 5425);
FORCEADD TAP..1
(-2625 3600);
FORCEPROP 3 LASTPIN (-2675 3600) SIG_NAME P5E_CPU0_P0_RX_BUF_DP<2>
J 0
(-2665 3610);
DISPLAY 0.659574 (-2665 3610);
PAINT MONO (-2665 3610);
DISPLAY INVISIBLE (-2665 3610);
FORCEPROP 1 LASTPIN (-2675 3600) BN 2
J 0
(-2687 3608);
DISPLAY 0.680851 (-2687 3608);
PAINT GREEN (-2687 3608);
FORCEPROP 2 LAST CDS_LIB standard
J 0
(-2625 3600);
DISPLAY INVISIBLE (-2625 3600);
FORCEPROP 1 LAST BODY_TYPE PLUMBING
J 0
(-2625 3650);
DISPLAY 0.872340 (-2625 3650);
PAINT GREEN (-2625 3650);
DISPLAY INVISIBLE (-2625 3650);
FORCEPROP 1 LAST HDL_TAP TRUE
J 0
(-2300 3475);
DISPLAY 0.872340 (-2300 3475);
DISPLAY INVISIBLE (-2300 3475);
FORCEPROP 1 LAST PATH I23
J 0
(-2627 3600);
DISPLAY 0.872340 (-2627 3600);
PAINT GREEN (-2627 3600);
DISPLAY INVISIBLE (-2627 3600);
FORCEADD TAP..1
(-2425 3500);
FORCEPROP 3 LASTPIN (-2475 3500) SIG_NAME P5E_CPU0_P0_RX_BUF_DN<2>
J 0
(-2465 3510);
DISPLAY 0.659574 (-2465 3510);
PAINT MONO (-2465 3510);
DISPLAY INVISIBLE (-2465 3510);
FORCEPROP 1 LASTPIN (-2475 3500) BN 2
J 0
(-2487 3508);
DISPLAY 0.680851 (-2487 3508);
PAINT GREEN (-2487 3508);
FORCEPROP 2 LAST CDS_LIB standard
J 0
(-2425 3500);
DISPLAY INVISIBLE (-2425 3500);
FORCEPROP 1 LAST BODY_TYPE PLUMBING
J 0
(-2425 3550);
DISPLAY 0.872340 (-2425 3550);
PAINT GREEN (-2425 3550);
DISPLAY INVISIBLE (-2425 3550);
FORCEPROP 1 LAST HDL_TAP TRUE
J 0
(-2100 3375);
DISPLAY 0.872340 (-2100 3375);
DISPLAY INVISIBLE (-2100 3375);
FORCEPROP 1 LAST PATH I24
J 0
(-2427 3500);
DISPLAY 0.872340 (-2427 3500);
PAINT GREEN (-2427 3500);
DISPLAY INVISIBLE (-2427 3500);
FORCEADD TAP..1
(-2625 3250);
FORCEPROP 3 LASTPIN (-2675 3250) SIG_NAME P5E_CPU0_P0_RX_BUF_DP<1>
J 0
(-2665 3260);
DISPLAY 0.659574 (-2665 3260);
PAINT MONO (-2665 3260);
DISPLAY INVISIBLE (-2665 3260);
FORCEPROP 1 LASTPIN (-2675 3250) BN 1
J 0
(-2687 3258);
DISPLAY 0.680851 (-2687 3258);
PAINT GREEN (-2687 3258);
FORCEPROP 2 LAST CDS_LIB standard
J 0
(-2625 3250);
DISPLAY INVISIBLE (-2625 3250);
FORCEPROP 1 LAST BODY_TYPE PLUMBING
J 0
(-2625 3300);
DISPLAY 0.872340 (-2625 3300);
PAINT GREEN (-2625 3300);
DISPLAY INVISIBLE (-2625 3300);
FORCEPROP 1 LAST HDL_TAP TRUE
J 0
(-2300 3125);
DISPLAY 0.872340 (-2300 3125);
DISPLAY INVISIBLE (-2300 3125);
FORCEPROP 1 LAST PATH I25
J 0
(-2627 3250);
DISPLAY 0.872340 (-2627 3250);
PAINT GREEN (-2627 3250);
DISPLAY INVISIBLE (-2627 3250);
FORCEADD OFFPAGE..1
R 2
(-1400 5375);
FORCEPROP 2 LAST $XR0 118 
J 0
(-1214 5375);
DISPLAY 0.638298 (-1214 5375);
PAINT MONO (-1214 5375);
FORCEPROP 2 LAST CDS_LIB standard
J 0
(-1400 5375);
DISPLAY INVISIBLE (-1400 5375);
FORCEPROP 1 LAST OFFPAGE TRUE
J 2
(-1725 5250);
DISPLAY 0.872340 (-1725 5250);
DISPLAY INVISIBLE (-1725 5250);
FORCEPROP 1 LAST COMMENT_BODY TRUE
J 2
(-1525 5275);
DISPLAY 0.872340 (-1525 5275);
PAINT GREEN (-1525 5275);
DISPLAY INVISIBLE (-1525 5275);
FORCEPROP 2 LAST PATH I26
J 0
(-1225 5450);
DISPLAY 0.680851 (-1225 5450);
DISPLAY INVISIBLE (-1225 5450);
FORCEADD OFFPAGE..1
R 2
(-1400 5450);
FORCEPROP 2 LAST $XR0 118 
J 0
(-1214 5450);
DISPLAY 0.638298 (-1214 5450);
PAINT MONO (-1214 5450);
FORCEPROP 2 LAST CDS_LIB standard
J 0
(-1400 5450);
DISPLAY INVISIBLE (-1400 5450);
FORCEPROP 1 LAST OFFPAGE TRUE
J 2
(-1725 5325);
DISPLAY 0.872340 (-1725 5325);
DISPLAY INVISIBLE (-1725 5325);
FORCEPROP 1 LAST COMMENT_BODY TRUE
J 2
(-1525 5350);
DISPLAY 0.872340 (-1525 5350);
PAINT GREEN (-1525 5350);
DISPLAY INVISIBLE (-1525 5350);
FORCEPROP 2 LAST PATH I27
J 0
(-1225 5525);
DISPLAY 0.680851 (-1225 5525);
DISPLAY INVISIBLE (-1225 5525);
FORCEADD TAP..1
(-2425 5250);
FORCEPROP 3 LASTPIN (-2475 5250) SIG_NAME P5E_CPU0_P0_RX_BUF_DN<7>
J 0
(-2465 5260);
DISPLAY 0.659574 (-2465 5260);
PAINT MONO (-2465 5260);
DISPLAY INVISIBLE (-2465 5260);
FORCEPROP 1 LASTPIN (-2475 5250) BN 7
J 0
(-2487 5258);
DISPLAY 0.680851 (-2487 5258);
PAINT GREEN (-2487 5258);
FORCEPROP 2 LAST CDS_LIB standard
J 0
(-2425 5250);
DISPLAY INVISIBLE (-2425 5250);
FORCEPROP 1 LAST BODY_TYPE PLUMBING
J 0
(-2425 5300);
DISPLAY 0.872340 (-2425 5300);
PAINT GREEN (-2425 5300);
DISPLAY INVISIBLE (-2425 5300);
FORCEPROP 1 LAST HDL_TAP TRUE
J 0
(-2100 5125);
DISPLAY 0.872340 (-2100 5125);
DISPLAY INVISIBLE (-2100 5125);
FORCEPROP 1 LAST PATH I28
J 0
(-2427 5250);
DISPLAY 0.872340 (-2427 5250);
PAINT GREEN (-2427 5250);
DISPLAY INVISIBLE (-2427 5250);
FORCEADD TAP..1
(-2625 5350);
FORCEPROP 3 LASTPIN (-2675 5350) SIG_NAME P5E_CPU0_P0_RX_BUF_DP<7>
J 0
(-2665 5360);
DISPLAY 0.659574 (-2665 5360);
PAINT MONO (-2665 5360);
DISPLAY INVISIBLE (-2665 5360);
FORCEPROP 1 LASTPIN (-2675 5350) BN 7
J 0
(-2687 5358);
DISPLAY 0.680851 (-2687 5358);
PAINT GREEN (-2687 5358);
FORCEPROP 2 LAST CDS_LIB standard
J 0
(-2625 5350);
DISPLAY INVISIBLE (-2625 5350);
FORCEPROP 1 LAST BODY_TYPE PLUMBING
J 0
(-2625 5400);
DISPLAY 0.872340 (-2625 5400);
PAINT GREEN (-2625 5400);
DISPLAY INVISIBLE (-2625 5400);
FORCEPROP 1 LAST HDL_TAP TRUE
J 0
(-2300 5225);
DISPLAY 0.872340 (-2300 5225);
DISPLAY INVISIBLE (-2300 5225);
FORCEPROP 1 LAST PATH I29
J 0
(-2627 5350);
DISPLAY 0.872340 (-2627 5350);
PAINT GREEN (-2627 5350);
DISPLAY INVISIBLE (-2627 5350);
FORCEADD PT5161LRS..2
(-3650 4100);
FORCEPROP 1 LAST LOCATION U6010
J 0
(-4000 5725);
DISPLAY 0.723404 (-4000 5725);
PAINT GREEN (-4000 5725);
FORCEPROP 0 LAST $SEC 2
J 0
(-4000 5875);
DISPLAY 0.680851 (-4000 5875);
PAINT MONO (-4000 5875);
DISPLAY INVISIBLE (-4000 5875);
FORCEPROP 0 LAST CDS_SEC 2
J 0
(-4000 5875);
DISPLAY 0.680851 (-4000 5875);
DISPLAY INVISIBLE (-4000 5875);
FORCEPROP 0 LASTPIN (-3200 5250) $PN CJ2
J 0
(-3190 5260);
DISPLAY 0.680851 (-3190 5260);
PAINT MONO (-3190 5260);
FORCEPROP 0 LASTPIN (-3200 4900) $PN CT2
J 0
(-3190 4910);
DISPLAY 0.680851 (-3190 4910);
PAINT MONO (-3190 4910);
FORCEPROP 0 LASTPIN (-3200 4550) $PN DC2
J 0
(-3190 4560);
DISPLAY 0.680851 (-3190 4560);
PAINT MONO (-3190 4560);
FORCEPROP 0 LASTPIN (-3200 4200) $PN DK2
J 0
(-3190 4210);
DISPLAY 0.680851 (-3190 4210);
PAINT MONO (-3190 4210);
FORCEPROP 0 LASTPIN (-3200 3850) $PN DU2
J 0
(-3190 3860);
DISPLAY 0.680851 (-3190 3860);
PAINT MONO (-3190 3860);
FORCEPROP 0 LASTPIN (-3200 3500) $PN ED2
J 0
(-3190 3510);
DISPLAY 0.680851 (-3190 3510);
PAINT MONO (-3190 3510);
FORCEPROP 0 LASTPIN (-3200 3150) $PN EL2
J 0
(-3190 3160);
DISPLAY 0.680851 (-3190 3160);
PAINT MONO (-3190 3160);
FORCEPROP 0 LASTPIN (-3200 2800) $PN EV2
J 0
(-3190 2810);
DISPLAY 0.680851 (-3190 2810);
PAINT MONO (-3190 2810);
FORCEPROP 0 LASTPIN (-3200 5350) $PN CL1
J 0
(-3190 5360);
DISPLAY 0.680851 (-3190 5360);
PAINT MONO (-3190 5360);
FORCEPROP 0 LASTPIN (-3200 5000) $PN CV1
J 0
(-3190 5010);
DISPLAY 0.680851 (-3190 5010);
PAINT MONO (-3190 5010);
FORCEPROP 0 LASTPIN (-3200 4650) $PN DE1
J 0
(-3190 4660);
DISPLAY 0.680851 (-3190 4660);
PAINT MONO (-3190 4660);
FORCEPROP 0 LASTPIN (-3200 4300) $PN DM1
J 0
(-3190 4310);
DISPLAY 0.680851 (-3190 4310);
PAINT MONO (-3190 4310);
FORCEPROP 0 LASTPIN (-3200 3950) $PN DW1
J 0
(-3190 3960);
DISPLAY 0.680851 (-3190 3960);
PAINT MONO (-3190 3960);
FORCEPROP 0 LASTPIN (-3200 3600) $PN EF1
J 0
(-3190 3610);
DISPLAY 0.680851 (-3190 3610);
PAINT MONO (-3190 3610);
FORCEPROP 0 LASTPIN (-3200 3250) $PN EN1
J 0
(-3190 3260);
DISPLAY 0.680851 (-3190 3260);
PAINT MONO (-3190 3260);
FORCEPROP 0 LASTPIN (-3200 2900) $PN EY1
J 0
(-3190 2910);
DISPLAY 0.680851 (-3190 2910);
PAINT MONO (-3190 2910);
FORCEPROP 1 LAST MATERIAL IC
J 0
(-4000 5575);
DISPLAY 0.723404 (-4000 5575);
PAINT GREEN (-4000 5575);
FORCEPROP 2 LAST PART_TYPE SMLF
J 0
(-4000 5825);
DISPLAY 0.680851 (-4000 5825);
FORCEPROP 2 LAST VALUE PT5161LRS
J 0
(-4000 5775);
DISPLAY 0.680851 (-4000 5775);
FORCEPROP 2 LAST CDS_LIB pure_quanta
J 0
(-3650 4100);
DISPLAY INVISIBLE (-3650 4100);
FORCEPROP 1 LAST CDS_LMAN_SYM_OUTLINE -350,1450,300,-1400
J 0
(-3650 4100);
DISPLAY 0.468085 (-3650 4100);
PAINT GREEN (-3650 4100);
DISPLAY INVISIBLE (-3650 4100);
FORCEPROP 1 LAST NEEDS_NO_SIZE TRUE
J 0
(-3650 4100);
DISPLAY 0.723404 (-3650 4100);
PAINT GREEN (-3650 4100);
DISPLAY INVISIBLE (-3650 4100);
FORCEPROP 1 LAST PATH I3
J 0
(-3650 4100);
DISPLAY 0.723404 (-3650 4100);
PAINT GREEN (-3650 4100);
DISPLAY INVISIBLE (-3650 4100);
FORCEPROP 1 LAST PART_NUMBER AJ051610U03
J 0
(-4000 5650);
DISPLAY 0.723404 (-4000 5650);
PAINT GREEN (-4000 5650);
DISPLAY INVISIBLE (-4000 5650);
FORCEADD TAP..1
(-2425 4900);
FORCEPROP 3 LASTPIN (-2475 4900) SIG_NAME P5E_CPU0_P0_RX_BUF_DN<6>
J 0
(-2465 4910);
DISPLAY 0.659574 (-2465 4910);
PAINT MONO (-2465 4910);
DISPLAY INVISIBLE (-2465 4910);
FORCEPROP 1 LASTPIN (-2475 4900) BN 6
J 0
(-2487 4908);
DISPLAY 0.680851 (-2487 4908);
PAINT GREEN (-2487 4908);
FORCEPROP 2 LAST CDS_LIB standard
J 0
(-2425 4900);
DISPLAY INVISIBLE (-2425 4900);
FORCEPROP 1 LAST BODY_TYPE PLUMBING
J 0
(-2425 4950);
DISPLAY 0.872340 (-2425 4950);
PAINT GREEN (-2425 4950);
DISPLAY INVISIBLE (-2425 4950);
FORCEPROP 1 LAST HDL_TAP TRUE
J 0
(-2100 4775);
DISPLAY 0.872340 (-2100 4775);
DISPLAY INVISIBLE (-2100 4775);
FORCEPROP 1 LAST PATH I30
J 0
(-2427 4900);
DISPLAY 0.872340 (-2427 4900);
PAINT GREEN (-2427 4900);
DISPLAY INVISIBLE (-2427 4900);
FORCEADD TAP..1
(-2625 5000);
FORCEPROP 3 LASTPIN (-2675 5000) SIG_NAME P5E_CPU0_P0_RX_BUF_DP<6>
J 0
(-2665 5010);
DISPLAY 0.659574 (-2665 5010);
PAINT MONO (-2665 5010);
DISPLAY INVISIBLE (-2665 5010);
FORCEPROP 1 LASTPIN (-2675 5000) BN 6
J 0
(-2687 5008);
DISPLAY 0.680851 (-2687 5008);
PAINT GREEN (-2687 5008);
FORCEPROP 2 LAST CDS_LIB standard
J 0
(-2625 5000);
DISPLAY INVISIBLE (-2625 5000);
FORCEPROP 1 LAST BODY_TYPE PLUMBING
J 0
(-2625 5050);
DISPLAY 0.872340 (-2625 5050);
PAINT GREEN (-2625 5050);
DISPLAY INVISIBLE (-2625 5050);
FORCEPROP 1 LAST HDL_TAP TRUE
J 0
(-2300 4875);
DISPLAY 0.872340 (-2300 4875);
DISPLAY INVISIBLE (-2300 4875);
FORCEPROP 1 LAST PATH I31
J 0
(-2627 5000);
DISPLAY 0.872340 (-2627 5000);
PAINT GREEN (-2627 5000);
DISPLAY INVISIBLE (-2627 5000);
FORCEADD TAP..1
(-2625 4650);
FORCEPROP 3 LASTPIN (-2675 4650) SIG_NAME P5E_CPU0_P0_RX_BUF_DP<5>
J 0
(-2665 4660);
DISPLAY 0.659574 (-2665 4660);
PAINT MONO (-2665 4660);
DISPLAY INVISIBLE (-2665 4660);
FORCEPROP 1 LASTPIN (-2675 4650) BN 5
J 0
(-2687 4658);
DISPLAY 0.680851 (-2687 4658);
PAINT GREEN (-2687 4658);
FORCEPROP 2 LAST CDS_LIB standard
J 0
(-2625 4650);
DISPLAY INVISIBLE (-2625 4650);
FORCEPROP 1 LAST BODY_TYPE PLUMBING
J 0
(-2625 4700);
DISPLAY 0.872340 (-2625 4700);
PAINT GREEN (-2625 4700);
DISPLAY INVISIBLE (-2625 4700);
FORCEPROP 1 LAST HDL_TAP TRUE
J 0
(-2300 4525);
DISPLAY 0.872340 (-2300 4525);
DISPLAY INVISIBLE (-2300 4525);
FORCEPROP 1 LAST PATH I32
J 0
(-2627 4650);
DISPLAY 0.872340 (-2627 4650);
PAINT GREEN (-2627 4650);
DISPLAY INVISIBLE (-2627 4650);
FORCEADD TAP..1
(-2425 4550);
FORCEPROP 3 LASTPIN (-2475 4550) SIG_NAME P5E_CPU0_P0_RX_BUF_DN<5>
J 0
(-2465 4560);
DISPLAY 0.659574 (-2465 4560);
PAINT MONO (-2465 4560);
DISPLAY INVISIBLE (-2465 4560);
FORCEPROP 1 LASTPIN (-2475 4550) BN 5
J 0
(-2487 4558);
DISPLAY 0.680851 (-2487 4558);
PAINT GREEN (-2487 4558);
FORCEPROP 2 LAST CDS_LIB standard
J 0
(-2425 4550);
DISPLAY INVISIBLE (-2425 4550);
FORCEPROP 1 LAST BODY_TYPE PLUMBING
J 0
(-2425 4600);
DISPLAY 0.872340 (-2425 4600);
PAINT GREEN (-2425 4600);
DISPLAY INVISIBLE (-2425 4600);
FORCEPROP 1 LAST HDL_TAP TRUE
J 0
(-2100 4425);
DISPLAY 0.872340 (-2100 4425);
DISPLAY INVISIBLE (-2100 4425);
FORCEPROP 1 LAST PATH I33
J 0
(-2427 4550);
DISPLAY 0.872340 (-2427 4550);
PAINT GREEN (-2427 4550);
DISPLAY INVISIBLE (-2427 4550);
FORCEADD TAP..1
(-2425 4200);
FORCEPROP 3 LASTPIN (-2475 4200) SIG_NAME P5E_CPU0_P0_RX_BUF_DN<4>
J 0
(-2465 4210);
DISPLAY 0.659574 (-2465 4210);
PAINT MONO (-2465 4210);
DISPLAY INVISIBLE (-2465 4210);
FORCEPROP 1 LASTPIN (-2475 4200) BN 4
J 0
(-2487 4208);
DISPLAY 0.680851 (-2487 4208);
PAINT GREEN (-2487 4208);
FORCEPROP 2 LAST CDS_LIB standard
J 0
(-2425 4200);
DISPLAY INVISIBLE (-2425 4200);
FORCEPROP 1 LAST BODY_TYPE PLUMBING
J 0
(-2425 4250);
DISPLAY 0.872340 (-2425 4250);
PAINT GREEN (-2425 4250);
DISPLAY INVISIBLE (-2425 4250);
FORCEPROP 1 LAST HDL_TAP TRUE
J 0
(-2100 4075);
DISPLAY 0.872340 (-2100 4075);
DISPLAY INVISIBLE (-2100 4075);
FORCEPROP 1 LAST PATH I34
J 0
(-2427 4200);
DISPLAY 0.872340 (-2427 4200);
PAINT GREEN (-2427 4200);
DISPLAY INVISIBLE (-2427 4200);
FORCEADD TAP..1
(-2625 4300);
FORCEPROP 3 LASTPIN (-2675 4300) SIG_NAME P5E_CPU0_P0_RX_BUF_DP<4>
J 0
(-2665 4310);
DISPLAY 0.659574 (-2665 4310);
PAINT MONO (-2665 4310);
DISPLAY INVISIBLE (-2665 4310);
FORCEPROP 1 LASTPIN (-2675 4300) BN 4
J 0
(-2687 4308);
DISPLAY 0.680851 (-2687 4308);
PAINT GREEN (-2687 4308);
FORCEPROP 2 LAST CDS_LIB standard
J 0
(-2625 4300);
DISPLAY INVISIBLE (-2625 4300);
FORCEPROP 1 LAST BODY_TYPE PLUMBING
J 0
(-2625 4350);
DISPLAY 0.872340 (-2625 4350);
PAINT GREEN (-2625 4350);
DISPLAY INVISIBLE (-2625 4350);
FORCEPROP 1 LAST HDL_TAP TRUE
J 0
(-2300 4175);
DISPLAY 0.872340 (-2300 4175);
DISPLAY INVISIBLE (-2300 4175);
FORCEPROP 1 LAST PATH I35
J 0
(-2627 4300);
DISPLAY 0.872340 (-2627 4300);
PAINT GREEN (-2627 4300);
DISPLAY INVISIBLE (-2627 4300);
FORCEADD TAP..1
(-2625 3950);
FORCEPROP 3 LASTPIN (-2675 3950) SIG_NAME P5E_CPU0_P0_RX_BUF_DP<3>
J 0
(-2665 3960);
DISPLAY 0.659574 (-2665 3960);
PAINT MONO (-2665 3960);
DISPLAY INVISIBLE (-2665 3960);
FORCEPROP 1 LASTPIN (-2675 3950) BN 3
J 0
(-2687 3958);
DISPLAY 0.680851 (-2687 3958);
PAINT GREEN (-2687 3958);
FORCEPROP 2 LAST CDS_LIB standard
J 0
(-2625 3950);
DISPLAY INVISIBLE (-2625 3950);
FORCEPROP 1 LAST BODY_TYPE PLUMBING
J 0
(-2625 4000);
DISPLAY 0.872340 (-2625 4000);
PAINT GREEN (-2625 4000);
DISPLAY INVISIBLE (-2625 4000);
FORCEPROP 1 LAST HDL_TAP TRUE
J 0
(-2300 3825);
DISPLAY 0.872340 (-2300 3825);
DISPLAY INVISIBLE (-2300 3825);
FORCEPROP 1 LAST PATH I36
J 0
(-2627 3950);
DISPLAY 0.872340 (-2627 3950);
PAINT GREEN (-2627 3950);
DISPLAY INVISIBLE (-2627 3950);
FORCEADD TAP..1
(-2425 3850);
FORCEPROP 3 LASTPIN (-2475 3850) SIG_NAME P5E_CPU0_P0_RX_BUF_DN<3>
J 0
(-2465 3860);
DISPLAY 0.659574 (-2465 3860);
PAINT MONO (-2465 3860);
DISPLAY INVISIBLE (-2465 3860);
FORCEPROP 1 LASTPIN (-2475 3850) BN 3
J 0
(-2487 3858);
DISPLAY 0.680851 (-2487 3858);
PAINT GREEN (-2487 3858);
FORCEPROP 2 LAST CDS_LIB standard
J 0
(-2425 3850);
DISPLAY INVISIBLE (-2425 3850);
FORCEPROP 1 LAST BODY_TYPE PLUMBING
J 0
(-2425 3900);
DISPLAY 0.872340 (-2425 3900);
PAINT GREEN (-2425 3900);
DISPLAY INVISIBLE (-2425 3900);
FORCEPROP 1 LAST HDL_TAP TRUE
J 0
(-2100 3725);
DISPLAY 0.872340 (-2100 3725);
DISPLAY INVISIBLE (-2100 3725);
FORCEPROP 1 LAST PATH I37
J 0
(-2427 3850);
DISPLAY 0.872340 (-2427 3850);
PAINT GREEN (-2427 3850);
DISPLAY INVISIBLE (-2427 3850);
FORCEADD TAP..1
(-2425 3150);
FORCEPROP 3 LASTPIN (-2475 3150) SIG_NAME P5E_CPU0_P0_RX_BUF_DN<1>
J 0
(-2465 3160);
DISPLAY 0.659574 (-2465 3160);
PAINT MONO (-2465 3160);
DISPLAY INVISIBLE (-2465 3160);
FORCEPROP 1 LASTPIN (-2475 3150) BN 1
J 0
(-2487 3158);
DISPLAY 0.680851 (-2487 3158);
PAINT GREEN (-2487 3158);
FORCEPROP 2 LAST CDS_LIB standard
J 0
(-2425 3150);
DISPLAY INVISIBLE (-2425 3150);
FORCEPROP 1 LAST BODY_TYPE PLUMBING
J 0
(-2425 3200);
DISPLAY 0.872340 (-2425 3200);
PAINT GREEN (-2425 3200);
DISPLAY INVISIBLE (-2425 3200);
FORCEPROP 1 LAST HDL_TAP TRUE
J 0
(-2100 3025);
DISPLAY 0.872340 (-2100 3025);
DISPLAY INVISIBLE (-2100 3025);
FORCEPROP 1 LAST PATH I38
J 0
(-2427 3150);
DISPLAY 0.872340 (-2427 3150);
PAINT GREEN (-2427 3150);
DISPLAY INVISIBLE (-2427 3150);
FORCEADD TAP..1
(-2625 2900);
FORCEPROP 3 LASTPIN (-2675 2900) SIG_NAME P5E_CPU0_P0_RX_BUF_DP<0>
J 0
(-2665 2910);
DISPLAY 0.659574 (-2665 2910);
PAINT MONO (-2665 2910);
DISPLAY INVISIBLE (-2665 2910);
FORCEPROP 1 LASTPIN (-2675 2900) BN 0
J 0
(-2687 2908);
DISPLAY 0.680851 (-2687 2908);
PAINT GREEN (-2687 2908);
FORCEPROP 2 LAST CDS_LIB standard
J 0
(-2625 2900);
DISPLAY INVISIBLE (-2625 2900);
FORCEPROP 1 LAST BODY_TYPE PLUMBING
J 0
(-2625 2950);
DISPLAY 0.872340 (-2625 2950);
PAINT GREEN (-2625 2950);
DISPLAY INVISIBLE (-2625 2950);
FORCEPROP 1 LAST HDL_TAP TRUE
J 0
(-2300 2775);
DISPLAY 0.872340 (-2300 2775);
DISPLAY INVISIBLE (-2300 2775);
FORCEPROP 1 LAST PATH I39
J 0
(-2627 2900);
DISPLAY 0.872340 (-2627 2900);
PAINT GREEN (-2627 2900);
DISPLAY INVISIBLE (-2627 2900);
FORCEADD PT5161LRS..1
(-8100 4075);
FORCEPROP 1 LAST LOCATION U6010
J 0
(-8450 5700);
DISPLAY 0.723404 (-8450 5700);
PAINT GREEN (-8450 5700);
FORCEPROP 0 LAST $SEC 1
J 0
(-8450 5850);
DISPLAY 0.680851 (-8450 5850);
PAINT MONO (-8450 5850);
DISPLAY INVISIBLE (-8450 5850);
FORCEPROP 0 LAST CDS_SEC 1
J 0
(-8450 5850);
DISPLAY 0.680851 (-8450 5850);
DISPLAY INVISIBLE (-8450 5850);
FORCEPROP 0 LASTPIN (-7650 5225) $PN N2
J 0
(-7640 5235);
DISPLAY 0.680851 (-7640 5235);
PAINT MONO (-7640 5235);
FORCEPROP 0 LASTPIN (-7650 4875) $PN Y2
J 0
(-7640 4885);
DISPLAY 0.680851 (-7640 4885);
PAINT MONO (-7640 4885);
FORCEPROP 0 LASTPIN (-7650 4525) $PN AG2
J 0
(-7640 4535);
DISPLAY 0.680851 (-7640 4535);
PAINT MONO (-7640 4535);
FORCEPROP 0 LASTPIN (-7650 4175) $PN AP2
J 0
(-7640 4185);
DISPLAY 0.680851 (-7640 4185);
PAINT MONO (-7640 4185);
FORCEPROP 0 LASTPIN (-7650 3825) $PN BA2
J 0
(-7640 3835);
DISPLAY 0.680851 (-7640 3835);
PAINT MONO (-7640 3835);
FORCEPROP 0 LASTPIN (-7650 3475) $PN BH2
J 0
(-7640 3485);
DISPLAY 0.680851 (-7640 3485);
PAINT MONO (-7640 3485);
FORCEPROP 0 LASTPIN (-7650 3125) $PN BR2
J 0
(-7640 3135);
DISPLAY 0.680851 (-7640 3135);
PAINT MONO (-7640 3135);
FORCEPROP 0 LASTPIN (-7650 2775) $PN CB2
J 0
(-7640 2785);
DISPLAY 0.680851 (-7640 2785);
PAINT MONO (-7640 2785);
FORCEPROP 0 LASTPIN (-7650 5325) $PN R1
J 0
(-7640 5335);
DISPLAY 0.680851 (-7640 5335);
PAINT MONO (-7640 5335);
FORCEPROP 0 LASTPIN (-7650 4975) $PN AB1
J 0
(-7640 4985);
DISPLAY 0.680851 (-7640 4985);
PAINT MONO (-7640 4985);
FORCEPROP 0 LASTPIN (-7650 4625) $PN AJ1
J 0
(-7640 4635);
DISPLAY 0.680851 (-7640 4635);
PAINT MONO (-7640 4635);
FORCEPROP 0 LASTPIN (-7650 4275) $PN AT1
J 0
(-7640 4285);
DISPLAY 0.680851 (-7640 4285);
PAINT MONO (-7640 4285);
FORCEPROP 0 LASTPIN (-7650 3925) $PN BC1
J 0
(-7640 3935);
DISPLAY 0.680851 (-7640 3935);
PAINT MONO (-7640 3935);
FORCEPROP 0 LASTPIN (-7650 3575) $PN BK1
J 0
(-7640 3585);
DISPLAY 0.680851 (-7640 3585);
PAINT MONO (-7640 3585);
FORCEPROP 0 LASTPIN (-7650 3225) $PN BU1
J 0
(-7640 3235);
DISPLAY 0.680851 (-7640 3235);
PAINT MONO (-7640 3235);
FORCEPROP 0 LASTPIN (-7650 2875) $PN CD1
J 0
(-7640 2885);
DISPLAY 0.680851 (-7640 2885);
PAINT MONO (-7640 2885);
FORCEPROP 2 LAST VALUE PT5161LRS
J 0
(-8450 5750);
DISPLAY 0.680851 (-8450 5750);
FORCEPROP 1 LAST MATERIAL IC
J 0
(-8450 5550);
DISPLAY 0.723404 (-8450 5550);
PAINT GREEN (-8450 5550);
FORCEPROP 2 LAST PART_TYPE SMLF
J 0
(-8450 5800);
DISPLAY 0.680851 (-8450 5800);
FORCEPROP 1 LAST NEEDS_NO_SIZE TRUE
J 0
(-8100 4075);
DISPLAY 0.723404 (-8100 4075);
PAINT GREEN (-8100 4075);
DISPLAY INVISIBLE (-8100 4075);
FORCEPROP 1 LAST CDS_LMAN_SYM_OUTLINE -350,1450,300,-1400
J 0
(-8100 4075);
DISPLAY 0.468085 (-8100 4075);
PAINT GREEN (-8100 4075);
DISPLAY INVISIBLE (-8100 4075);
FORCEPROP 2 LAST CDS_LIB pure_quanta
J 0
(-8100 4075);
DISPLAY INVISIBLE (-8100 4075);
FORCEPROP 1 LAST PATH I4
J 0
(-8100 4075);
DISPLAY 0.723404 (-8100 4075);
PAINT GREEN (-8100 4075);
DISPLAY INVISIBLE (-8100 4075);
FORCEPROP 1 LAST PART_NUMBER AJ051610U03
J 0
(-8450 5625);
DISPLAY 0.723404 (-8450 5625);
PAINT GREEN (-8450 5625);
DISPLAY INVISIBLE (-8450 5625);
FORCEADD TAP..1
(-2425 2800);
FORCEPROP 3 LASTPIN (-2475 2800) SIG_NAME P5E_CPU0_P0_RX_BUF_DN<0>
J 0
(-2465 2810);
DISPLAY 0.659574 (-2465 2810);
PAINT MONO (-2465 2810);
DISPLAY INVISIBLE (-2465 2810);
FORCEPROP 1 LASTPIN (-2475 2800) BN 0
J 0
(-2487 2808);
DISPLAY 0.680851 (-2487 2808);
PAINT GREEN (-2487 2808);
FORCEPROP 2 LAST CDS_LIB standard
J 0
(-2425 2800);
DISPLAY INVISIBLE (-2425 2800);
FORCEPROP 1 LAST BODY_TYPE PLUMBING
J 0
(-2425 2850);
DISPLAY 0.872340 (-2425 2850);
PAINT GREEN (-2425 2850);
DISPLAY INVISIBLE (-2425 2850);
FORCEPROP 1 LAST HDL_TAP TRUE
J 0
(-2100 2675);
DISPLAY 0.872340 (-2100 2675);
DISPLAY INVISIBLE (-2100 2675);
FORCEPROP 1 LAST PATH I40
J 0
(-2427 2800);
DISPLAY 0.872340 (-2427 2800);
PAINT GREEN (-2427 2800);
DISPLAY INVISIBLE (-2427 2800);
FORCEADD TAP..1
(-7075 2875);
FORCEPROP 3 LASTPIN (-7125 2875) SIG_NAME P5E_CPU0_P0_RX_BUF_DP<8>
J 0
(-7115 2885);
DISPLAY 0.659574 (-7115 2885);
PAINT MONO (-7115 2885);
DISPLAY INVISIBLE (-7115 2885);
FORCEPROP 1 LASTPIN (-7125 2875) BN 8
J 0
(-7137 2883);
DISPLAY 0.680851 (-7137 2883);
PAINT GREEN (-7137 2883);
FORCEPROP 2 LAST CDS_LIB standard
J 0
(-7075 2875);
DISPLAY INVISIBLE (-7075 2875);
FORCEPROP 1 LAST BODY_TYPE PLUMBING
J 0
(-7075 2925);
DISPLAY 0.872340 (-7075 2925);
PAINT GREEN (-7075 2925);
DISPLAY INVISIBLE (-7075 2925);
FORCEPROP 1 LAST HDL_TAP TRUE
J 0
(-6750 2750);
DISPLAY 0.872340 (-6750 2750);
DISPLAY INVISIBLE (-6750 2750);
FORCEPROP 1 LAST PATH I5
J 0
(-7077 2875);
DISPLAY 0.872340 (-7077 2875);
PAINT GREEN (-7077 2875);
DISPLAY INVISIBLE (-7077 2875);
FORCEADD TAP..1
(-6875 2775);
FORCEPROP 3 LASTPIN (-6925 2775) SIG_NAME P5E_CPU0_P0_RX_BUF_DN<8>
J 0
(-6915 2785);
DISPLAY 0.659574 (-6915 2785);
PAINT MONO (-6915 2785);
DISPLAY INVISIBLE (-6915 2785);
FORCEPROP 1 LASTPIN (-6925 2775) BN 8
J 0
(-6937 2783);
DISPLAY 0.680851 (-6937 2783);
PAINT GREEN (-6937 2783);
FORCEPROP 2 LAST CDS_LIB standard
J 0
(-6875 2775);
DISPLAY INVISIBLE (-6875 2775);
FORCEPROP 1 LAST BODY_TYPE PLUMBING
J 0
(-6875 2825);
DISPLAY 0.872340 (-6875 2825);
PAINT GREEN (-6875 2825);
DISPLAY INVISIBLE (-6875 2825);
FORCEPROP 1 LAST HDL_TAP TRUE
J 0
(-6550 2650);
DISPLAY 0.872340 (-6550 2650);
DISPLAY INVISIBLE (-6550 2650);
FORCEPROP 1 LAST PATH I6
J 0
(-6877 2775);
DISPLAY 0.872340 (-6877 2775);
PAINT GREEN (-6877 2775);
DISPLAY INVISIBLE (-6877 2775);
FORCEADD TAP..1
(-7075 3225);
FORCEPROP 3 LASTPIN (-7125 3225) SIG_NAME P5E_CPU0_P0_RX_BUF_DP<9>
J 0
(-7115 3235);
DISPLAY 0.659574 (-7115 3235);
PAINT MONO (-7115 3235);
DISPLAY INVISIBLE (-7115 3235);
FORCEPROP 1 LASTPIN (-7125 3225) BN 9
J 0
(-7137 3233);
DISPLAY 0.680851 (-7137 3233);
PAINT GREEN (-7137 3233);
FORCEPROP 2 LAST CDS_LIB standard
J 0
(-7075 3225);
DISPLAY INVISIBLE (-7075 3225);
FORCEPROP 1 LAST BODY_TYPE PLUMBING
J 0
(-7075 3275);
DISPLAY 0.872340 (-7075 3275);
PAINT GREEN (-7075 3275);
DISPLAY INVISIBLE (-7075 3275);
FORCEPROP 1 LAST HDL_TAP TRUE
J 0
(-6750 3100);
DISPLAY 0.872340 (-6750 3100);
DISPLAY INVISIBLE (-6750 3100);
FORCEPROP 1 LAST PATH I7
J 0
(-7077 3225);
DISPLAY 0.872340 (-7077 3225);
PAINT GREEN (-7077 3225);
DISPLAY INVISIBLE (-7077 3225);
FORCEADD TAP..1
(-6875 3125);
FORCEPROP 3 LASTPIN (-6925 3125) SIG_NAME P5E_CPU0_P0_RX_BUF_DN<9>
J 0
(-6915 3135);
DISPLAY 0.659574 (-6915 3135);
PAINT MONO (-6915 3135);
DISPLAY INVISIBLE (-6915 3135);
FORCEPROP 1 LASTPIN (-6925 3125) BN 9
J 0
(-6937 3133);
DISPLAY 0.680851 (-6937 3133);
PAINT GREEN (-6937 3133);
FORCEPROP 2 LAST CDS_LIB standard
J 0
(-6875 3125);
DISPLAY INVISIBLE (-6875 3125);
FORCEPROP 1 LAST BODY_TYPE PLUMBING
J 0
(-6875 3175);
DISPLAY 0.872340 (-6875 3175);
PAINT GREEN (-6875 3175);
DISPLAY INVISIBLE (-6875 3175);
FORCEPROP 1 LAST HDL_TAP TRUE
J 0
(-6550 3000);
DISPLAY 0.872340 (-6550 3000);
DISPLAY INVISIBLE (-6550 3000);
FORCEPROP 1 LAST PATH I8
J 0
(-6877 3125);
DISPLAY 0.872340 (-6877 3125);
PAINT GREEN (-6877 3125);
DISPLAY INVISIBLE (-6877 3125);
FORCEADD TAP..1
(-6875 3475);
FORCEPROP 3 LASTPIN (-6925 3475) SIG_NAME P5E_CPU0_P0_RX_BUF_DN<10>
J 0
(-6915 3485);
DISPLAY 0.659574 (-6915 3485);
PAINT MONO (-6915 3485);
DISPLAY INVISIBLE (-6915 3485);
FORCEPROP 1 LASTPIN (-6925 3475) BN 10
J 0
(-6937 3483);
DISPLAY 0.680851 (-6937 3483);
PAINT GREEN (-6937 3483);
FORCEPROP 2 LAST CDS_LIB standard
J 0
(-6875 3475);
DISPLAY INVISIBLE (-6875 3475);
FORCEPROP 1 LAST BODY_TYPE PLUMBING
J 0
(-6875 3525);
DISPLAY 0.872340 (-6875 3525);
PAINT GREEN (-6875 3525);
DISPLAY INVISIBLE (-6875 3525);
FORCEPROP 1 LAST HDL_TAP TRUE
J 0
(-6550 3350);
DISPLAY 0.872340 (-6550 3350);
DISPLAY INVISIBLE (-6550 3350);
FORCEPROP 1 LAST PATH I9
J 0
(-6877 3475);
DISPLAY 0.872340 (-6877 3475);
PAINT GREEN (-6877 3475);
DISPLAY INVISIBLE (-6877 3475);
FORCEADD QUANTA_TITLE_BLOCK_C..1
(0 0);
FORCEPROP 0 LAST CDS_CON_LAST_MODIFIED Thu Sep 14 16:12:49 2023
J 0
(-1885 15);
DISPLAY INVISIBLE (-1885 15);
FORCEPROP 1 LAST CUSTOM_TXT_CDS <CON_LAST_MODIFIED>
J 0
(-1885 15);
DISPLAY 0.978723 (-1885 15);
FORCEPROP 2 LAST CUSTOM_TXT_CDS <XR_PAGE_TITLE>
J 0
(-7890 5250);
DISPLAY 0.638298 (-7890 5250);
PAINT PINK (-7890 5250);
DISPLAY INVISIBLE (-7890 5250);
FORCEPROP 1 LAST CUSTOM_TXT_CDS <NAME_2>
J 0
(-3175 50);
FORCEPROP 1 LAST CUSTOM_TXT_CDS <NAME_1>
J 0
(-3175 175);
FORCEPROP 1 LAST CUSTOM_TXT_CDS <Q_NUMBER>
J 0
(-1403 103);
DISPLAY 1.212766 (-1403 103);
FORCEPROP 1 LAST CUSTOM_TXT_CDS <Q_PROJ>
J 0
(-2382 102);
DISPLAY 1.212766 (-2382 102);
FORCEPROP 1 LAST CUSTOM_TXT_CDS <Q_REV>
J 0
(-184 103);
DISPLAY 1.212766 (-184 103);
FORCEPROP 1 LAST CUSTOM_TXT_CDS <CON_PAGE_NUM> OF <CON_TOTAL_PAGES>
J 0
(-446 18);
DISPLAY 0.978723 (-446 18);
FORCEPROP 1 LAST Q_TITLE RETIMER_CPU0_P0(3)
J 0
(-9366 26);
DISPLAY 2.446809 (-9366 26);
PAINT GREEN (-9366 26);
FORCEPROP 2 LAST PAGE_BORDER TRUE
J 0
(-7890 5250);
DISPLAY 0.638298 (-7890 5250);
PAINT PINK (-7890 5250);
DISPLAY INVISIBLE (-7890 5250);
FORCEPROP 1 LAST CDS_LMAN_SYM_OUTLINE -9475,6775,100,-125
J 0
(0 0);
DISPLAY 0.468085 (0 0);
PAINT GREEN (0 0);
DISPLAY INVISIBLE (0 0);
FORCEPROP 2 LAST CDS_LIB pure_quanta
J 0
(0 0);
DISPLAY INVISIBLE (0 0);
FORCEPROP 2 LAST CDS_XR_PAGE_TITLE CR-275 : @T6G_MB_LIB.T6G(SCH_1):PAGE275
J 0
(-7890 5250);
DISPLAY 0.638298 (-7890 5250);
PAINT PINK (-7890 5250);
DISPLAY INVISIBLE (-7890 5250);
FORCEPROP 1 LAST Q_DEPT BU9
J 1
(-3763 49);
DISPLAY 1.957447 (-3763 49);
PAINT GREEN (-3763 49);
DISPLAY INVISIBLE (-3763 49);
FORCEPROP 1 LAST COMMENT_BODY TRUE
J 0
(12 -13);
DISPLAY 0.978723 (12 -13);
PAINT GREEN (12 -13);
DISPLAY INVISIBLE (12 -13);
WIRE 17 -1 (-2575 5450)(-2575 5375);
WIRE 17 -1 (-2575 5450)(-1450 5450);
FORCEPROP 2 LAST SIG_NAME P5E_CPU0_P0_RX_BUF_DP<7:0>
J 0
(-2310 5460);
DISPLAY 0.680851 (-2310 5460);
PAINT WHITE (-2310 5460);
WIRE 17 -1 (-2375 3175)(-2375 2825);
WIRE 17 -1 (-2375 3525)(-2375 3175);
WIRE 17 -1 (-2375 3875)(-2375 3525);
WIRE 17 -1 (-2375 3875)(-2375 4225);
WIRE 17 -1 (-2375 4575)(-2375 4225);
WIRE 17 -1 (-2375 4925)(-2375 4575);
WIRE 17 -1 (-2375 5275)(-2375 4925);
WIRE 17 -1 (-2375 5375)(-2375 5275);
WIRE 17 -1 (-2375 5375)(-1450 5375);
FORCEPROP 2 LAST SIG_NAME P5E_CPU0_P0_RX_BUF_DN<7:0>
J 0
(-2310 5385);
DISPLAY 0.680851 (-2310 5385);
PAINT WHITE (-2310 5385);
WIRE 17 -1 (-2575 5375)(-2575 5025);
WIRE 17 -1 (-2575 5025)(-2575 4675);
WIRE 17 -1 (-2575 4675)(-2575 4325);
WIRE 17 -1 (-2575 3975)(-2575 4325);
WIRE 17 -1 (-2575 3975)(-2575 3625);
WIRE 17 -1 (-2575 3625)(-2575 3275);
WIRE 17 -1 (-2575 3275)(-2575 2925);
WIRE 17 -1 (-6825 4900)(-6825 4550);
WIRE 17 -1 (-6825 5250)(-6825 4900);
WIRE 17 -1 (-6825 4550)(-6825 4200);
WIRE 17 -1 (-6825 3850)(-6825 4200);
WIRE 17 -1 (-6825 5350)(-6825 5250);
WIRE 17 -1 (-6825 5350)(-5900 5350);
FORCEPROP 2 LAST SIG_NAME P5E_CPU0_P0_RX_BUF_DN<15:8>
J 0
(-6760 5360);
DISPLAY 0.680851 (-6760 5360);
PAINT WHITE (-6760 5360);
WIRE 17 -1 (-6825 3150)(-6825 2800);
WIRE 17 -1 (-6825 3500)(-6825 3150);
WIRE 17 -1 (-6825 3850)(-6825 3500);
WIRE 17 -1 (-7025 5350)(-7025 5000);
WIRE 17 -1 (-7025 5425)(-7025 5350);
WIRE 17 -1 (-7025 5000)(-7025 4650);
WIRE 17 -1 (-7025 4650)(-7025 4300);
WIRE 17 -1 (-7025 5425)(-5900 5425);
FORCEPROP 2 LAST SIG_NAME P5E_CPU0_P0_RX_BUF_DP<15:8>
J 0
(-6760 5435);
DISPLAY 0.680851 (-6760 5435);
PAINT WHITE (-6760 5435);
WIRE 17 -1 (-7025 3250)(-7025 2900);
WIRE 17 -1 (-7025 3600)(-7025 3250);
WIRE 17 -1 (-7025 3950)(-7025 3600);
WIRE 17 -1 (-7025 3950)(-7025 4300);
WIRE 16 -1 (-3200 5250)(-2475 5250);
WIRE 16 -1 (-3200 3150)(-2475 3150);
WIRE 16 -1 (-7650 3475)(-6925 3475);
WIRE 16 -1 (-7650 4875)(-6925 4875);
WIRE 16 -1 (-7650 4175)(-6925 4175);
WIRE 16 -1 (-7650 3825)(-6925 3825);
WIRE 16 -1 (-7650 3225)(-7125 3225);
WIRE 16 -1 (-7650 3575)(-7125 3575);
WIRE 16 -1 (-7650 4275)(-7125 4275);
WIRE 16 -1 (-7650 4625)(-7125 4625);
WIRE 16 -1 (-7650 3925)(-7125 3925);
WIRE 16 -1 (-3200 4300)(-2675 4300);
WIRE 16 -1 (-3200 3250)(-2675 3250);
WIRE 16 -1 (-7650 5325)(-7125 5325);
WIRE 16 -1 (-7650 2875)(-7125 2875);
WIRE 16 -1 (-7650 3125)(-6925 3125);
WIRE 16 -1 (-7650 4975)(-7125 4975);
WIRE 16 -1 (-7650 2775)(-6925 2775);
WIRE 16 -1 (-7650 5225)(-6925 5225);
WIRE 16 -1 (-7650 4525)(-6925 4525);
WIRE 16 -1 (-3200 2900)(-2675 2900);
WIRE 16 -1 (-3200 3500)(-2475 3500);
WIRE 16 -1 (-3200 3600)(-2675 3600);
WIRE 16 -1 (-3200 3850)(-2475 3850);
WIRE 16 -1 (-3200 3950)(-2675 3950);
WIRE 16 -1 (-3200 4200)(-2475 4200);
WIRE 16 -1 (-3200 4550)(-2475 4550);
WIRE 16 -1 (-3200 4650)(-2675 4650);
WIRE 16 -1 (-3200 4900)(-2475 4900);
WIRE 16 -1 (-3200 5000)(-2675 5000);
WIRE 16 -1 (-3200 2800)(-2475 2800);
WIRE 16 -1 (-3200 5350)(-2675 5350);
FORCENOTE
P5E_CPU0_P0_RX_BUF_DP/DN<0-15> LANE REVERSAL
(-8850 6325) 0;
DISPLAY LEFT (-8850 6325);
DISPLAY 2.000000 (-8850 6325);
FORCENOTE
EXAMAX TO RETIMER
(-8475 1950) 0;
DISPLAY LEFT (-8475 1950);
DISPLAY 3.148936 (-8475 1950);
FORCENOTE
EXAMAX TO RETIMER
(-3925 1925) 0;
DISPLAY LEFT (-3925 1925);
DISPLAY 3.148936 (-3925 1925);
QUIT
